# T6G (Grand Teton) — schematic netlist excerpt (pin names and nets, part order shuffled) for the footprints in the layout excerpt that follows; sources: Cadence DE-HDL packaged netlist, KiCad conversion of 04192023_DAF0TMB3IC0_F0TG_MB_C_brd_V02_OCP.brd

PR460  Q_RES  49.9 1% CHIP  pkg 0402LF  page 217 : A = VSENSE_VSS_SENSE_B_P1 ; B = GND
R8312  Q_RES  0 5% CHIP  pkg 0402LF  page 193 : A = PVDDCR_CPU0_P0_EN ; B = PVDDCR_CPU0_P0_EN_R

(kicad_pcb
	(version 20260206)
	(generator "pcbnew")
	(generator_version "10.0")
	(general
		(thickness 1.6)
		(legacy_teardrops no)
	)
	(paper "A4")
	(title_block
		(title "04192023_DAF0TMB3IC0_F0TG_MB_C_brd_V02_OCP.brd")
		(comment 1 "Grand Teton / footprints 1856-1857 of 8354")
	)
	(layers
		(0 "F.Cu" signal "TOP")
		(4 "In1.Cu" signal "GND")
		(6 "In2.Cu" signal "IN1")
		(8 "In3.Cu" signal "GND1")
		(10 "In4.Cu" signal "IN2")
		(12 "In5.Cu" signal "GND2")
		(14 "In6.Cu" signal "IN3")
		(16 "In7.Cu" signal "GND3")
		(18 "In8.Cu" signal "VCC")
		(20 "In9.Cu" signal "VCC1")
		(22 "In10.Cu" signal "GND4")
		(24 "In11.Cu" signal "IN4")
		(26 "In12.Cu" signal "GND5")
		(28 "In13.Cu" signal "IN5")
		(30 "In14.Cu" signal "GND6")
		(32 "In15.Cu" signal "IN6")
		(34 "In16.Cu" signal "GND7")
		(2 "B.Cu" signal "BOTTOM")
		(9 "F.Adhes" user "F.Adhesive")
		(11 "B.Adhes" user "B.Adhesive")
		(13 "F.Paste" user "Package Geometry/Pastemask Top")
		(15 "B.Paste" user "Package Geometry/Pastemask Bottom")
		(5 "F.SilkS" user "Ref Des/Silkscreen Top")
		(7 "B.SilkS" user "Ref Des/Silkscreen Bottom")
		(1 "F.Mask" user "Board Geometry/Soldermask Top")
		(3 "B.Mask" user "Board Geometry/Soldermask Bottom")
		(17 "Dwgs.User" user "User.Drawings")
		(19 "Cmts.User" user "User.Comments")
		(21 "Eco1.User" user "User.Eco1")
		(23 "Eco2.User" user "User.Eco2")
		(25 "Edge.Cuts" user "Board Geometry/Outline")
		(27 "Margin" user)
		(31 "F.CrtYd" user "Package Geometry/Place Bound Top")
		(29 "B.CrtYd" user "Package Geometry/Place Bound Bottom")
		(35 "F.Fab" user "Ref Des/Assembly Top")
		(33 "B.Fab" user "Ref Des/Assembly Bottom")
	)
	(footprint ""
		(layer "F.Cu")
		(at 372.937278 -140.456158)
		(property "Reference" "R8312"
			(at 0 0 0)
			(layer "F.SilkS")
			(hide yes)
			(effects
				(font
					(size 1.27 1.27)
				)
			)
		)
		(property "Value" ""
			(at 0 0 0)
			(layer "F.Fab")
			(effects
				(font
					(size 1.27 1.27)
				)
			)
		)
		(duplicate_pad_numbers_are_jumpers no)
		(fp_line
			(start -0.7874 -0.4064)
			(end 0.7874 -0.4064)
			(stroke
				(width 0.1524)
				(type default)
			)
			(layer "F.SilkS")
		)
		(fp_line
			(start -0.7874 0.4064)
			(end -0.7874 -0.4064)
			(stroke
				(width 0.1524)
				(type default)
			)
			(layer "F.SilkS")
		)
		(fp_line
			(start 0.7874 -0.4064)
			(end 0.7874 0.4064)
			(stroke
				(width 0.1524)
				(type default)
			)
			(layer "F.SilkS")
		)
		(fp_line
			(start 0.7874 0.4064)
			(end -0.7874 0.4064)
			(stroke
				(width 0.1524)
				(type default)
			)
			(layer "F.SilkS")
		)
		(fp_line
			(start -0.67945 -0.305054)
			(end -0.12065 -0.305054)
			(stroke
				(width 0.1)
				(type default)
			)
			(layer "F.Fab")
		)
		(fp_line
			(start -0.67945 0.3048)
			(end -0.67945 -0.305054)
			(stroke
				(width 0.1)
				(type default)
			)
			(layer "F.Fab")
		)
		(fp_line
			(start -0.12065 -0.305054)
			(end -0.12065 -0.2794)
			(stroke
				(width 0.1)
				(type default)
			)
			(layer "F.Fab")
		)
		(fp_line
			(start -0.12065 -0.2794)
			(end 0.12065 -0.2794)
			(stroke
				(width 0.1)
				(type default)
			)
			(layer "F.Fab")
		)
		(fp_line
			(start -0.12065 0.2794)
			(end -0.12065 0.3048)
			(stroke
				(width 0.1)
				(type default)
			)
			(layer "F.Fab")
		)
		(fp_line
			(start -0.12065 0.3048)
			(end -0.67945 0.3048)
			(stroke
				(width 0.1)
				(type default)
			)
			(layer "F.Fab")
		)
		(fp_line
			(start 0.120396 0.2794)
			(end -0.12065 0.2794)
			(stroke
				(width 0.1)
				(type default)
			)
			(layer "F.Fab")
		)
		(fp_line
			(start 0.120396 0.3048)
			(end 0.120396 0.2794)
			(stroke
				(width 0.1)
				(type default)
			)
			(layer "F.Fab")
		)
		(fp_line
			(start 0.12065 -0.3048)
			(end 0.67945 -0.3048)
			(stroke
				(width 0.1)
				(type default)
			)
			(layer "F.Fab")
		)
		(fp_line
			(start 0.12065 -0.2794)
			(end 0.12065 -0.3048)
			(stroke
				(width 0.1)
				(type default)
			)
			(layer "F.Fab")
		)
		(fp_line
			(start 0.67945 -0.3048)
			(end 0.67945 0.3048)
			(stroke
				(width 0.1)
				(type default)
			)
			(layer "F.Fab")
		)
		(fp_line
			(start 0.67945 0.3048)
			(end 0.120396 0.3048)
			(stroke
				(width 0.1)
				(type default)
			)
			(layer "F.Fab")
		)
		(pad "1" smd circle
			(at -0.40005 0)
			(size 0 0)
			(layers "F.Cu" "F.Mask" "F.Paste")
			(net "PVDDCR_CPU0_P0_EN")
		)
		(pad "2" smd circle
			(at 0.40005 0)
			(size 0 0)
			(layers "F.Cu" "F.Mask" "F.Paste")
			(net "PVDDCR_CPU0_P0_EN_R")
		)
	)
	(footprint ""
		(layer "F.Cu")
		(at 22.49805 -333.151226)
		(property "Reference" "PR460"
			(at 0 0 0)
			(layer "F.SilkS")
			(hide yes)
			(effects
				(font
					(size 1.27 1.27)
				)
			)
		)
		(property "Value" ""
			(at 0 0 0)
			(layer "F.Fab")
			(effects
				(font
					(size 1.27 1.27)
				)
			)
		)
		(duplicate_pad_numbers_are_jumpers no)
		(fp_line
			(start -0.7874 -0.4064)
			(end 0.7874 -0.4064)
			(stroke
				(width 0.1524)
				(type default)
			)
			(layer "F.SilkS")
		)
		(fp_line
			(start -0.7874 0.4064)
			(end -0.7874 -0.4064)
			(stroke
				(width 0.1524)
				(type default)
			)
			(layer "F.SilkS")
		)
		(fp_line
			(start 0.7874 -0.4064)
			(end 0.7874 0.4064)
			(stroke
				(width 0.1524)
				(type default)
			)
			(layer "F.SilkS")
		)
		(fp_line
			(start 0.7874 0.4064)
			(end -0.7874 0.4064)
			(stroke
				(width 0.1524)
				(type default)
			)
			(layer "F.SilkS")
		)
		(fp_line
			(start -0.67945 -0.305054)
			(end -0.12065 -0.305054)
			(stroke
				(width 0.1)
				(type default)
			)
			(layer "F.Fab")
		)
		(fp_line
			(start -0.67945 0.3048)
			(end -0.67945 -0.305054)
			(stroke
				(width 0.1)
				(type default)
			)
			(layer "F.Fab")
		)
		(fp_line
			(start -0.12065 -0.305054)
			(end -0.12065 -0.2794)
			(stroke
				(width 0.1)
				(type default)
			)
			(layer "F.Fab")
		)
		(fp_line
			(start -0.12065 -0.2794)
			(end 0.12065 -0.2794)
			(stroke
				(width 0.1)
				(type default)
			)
			(layer "F.Fab")
		)
		(fp_line
			(start -0.12065 0.2794)
			(end -0.12065 0.3048)
			(stroke
				(width 0.1)
				(type default)
			)
			(layer "F.Fab")
		)
		(fp_line
			(start -0.12065 0.3048)
			(end -0.67945 0.3048)
			(stroke
				(width 0.1)
				(type default)
			)
			(layer "F.Fab")
		)
		(fp_line
			(start 0.120396 0.2794)
			(end -0.12065 0.2794)
			(stroke
				(width 0.1)
				(type default)
			)
			(layer "F.Fab")
		)
		(fp_line
			(start 0.120396 0.3048)
			(end 0.120396 0.2794)
			(stroke
				(width 0.1)
				(type default)
			)
			(layer "F.Fab")
		)
		(fp_line
			(start 0.12065 -0.3048)
			(end 0.67945 -0.3048)
			(stroke
				(width 0.1)
				(type default)
			)
			(layer "F.Fab")
		)
		(fp_line
			(start 0.12065 -0.2794)
			(end 0.12065 -0.3048)
			(stroke
				(width 0.1)
				(type default)
			)
			(layer "F.Fab")
		)
		(fp_line
			(start 0.67945 -0.3048)
			(end 0.67945 0.3048)
			(stroke
				(width 0.1)
				(type default)
			)
			(layer "F.Fab")
		)
		(fp_line
			(start 0.67945 0.3048)
			(end 0.120396 0.3048)
			(stroke
				(width 0.1)
				(type default)
			)
			(layer "F.Fab")
		)
		(pad "1" smd circle
			(at -0.40005 0)
			(size 0 0)
			(layers "F.Cu" "F.Mask" "F.Paste")
			(net "VSENSE_VSS_SENSE_B_P1")
		)
		(pad "2" smd circle
			(at 0.40005 0)
			(size 0 0)
			(layers "F.Cu" "F.Mask" "F.Paste")
			(net "GND")
		)
	)
)
